(kicad_pcb
	(version 20260206)
	(generator "pcbnew")
	(generator_version "10.0")
	(general
		(thickness 1.6)
		(legacy_teardrops no)
	)
	(paper "A4")
	(title_block
		(title "Bryce Canyon_F.DPB_16315-1-OCP.brd")
		(comment 1 "Bryce Canyon / footprints 19-25 of 2223")
	)
	(layers
		(0 "F.Cu" signal "TOP")
		(4 "In1.Cu" signal "L2GND")
		(6 "In2.Cu" signal "L3")
		(8 "In3.Cu" signal "L4GND")
		(10 "In4.Cu" signal "L5")
		(12 "In5.Cu" signal "L6VCC")
		(14 "In6.Cu" signal "L7VCC")
		(16 "In7.Cu" signal "L8")
		(18 "In8.Cu" signal "L9GND")
		(20 "In9.Cu" signal "L10")
		(22 "In10.Cu" signal "L11GND")
		(2 "B.Cu" signal "BOTTOM")
		(9 "F.Adhes" user "F.Adhesive")
		(11 "B.Adhes" user "B.Adhesive")
		(13 "F.Paste" user "Package Geometry/Pastemask Top")
		(15 "B.Paste" user "Package Geometry/Pastemask Bottom")
		(5 "F.SilkS" user "Ref Des/Silkscreen Top")
		(7 "B.SilkS" user "Ref Des/Silkscreen Bottom")
		(1 "F.Mask" user "Board Geometry/Soldermask Top")
		(3 "B.Mask" user "Board Geometry/Soldermask Bottom")
		(17 "Dwgs.User" user "User.Drawings")
		(19 "Cmts.User" user "User.Comments")
		(21 "Eco1.User" user "User.Eco1")
		(23 "Eco2.User" user "User.Eco2")
		(25 "Edge.Cuts" user "Board Geometry/Outline")
		(27 "Margin" user)
		(31 "F.CrtYd" user "Package Geometry/Place Bound Top")
		(29 "B.CrtYd" user "Package Geometry/Place Bound Bottom")
		(35 "F.Fab" user "Ref Des/Assembly Top")
		(33 "B.Fab" user "Ref Des/Assembly Bottom")
	)
	(footprint ""
		(layer "F.Cu")
		(at 378.249942 -324.39991)
		(property "Reference" "RLED33"
			(at 0 0 0)
			(layer "F.SilkS")
			(hide yes)
			(effects
				(font
					(size 1.27 1.27)
				)
			)
		)
		(property "Value" "LED-BY-19-GP"
			(at -2.132076 1.414018 0)
			(unlocked yes)
			(layer "F.Fab")
			(hide yes)
			(effects
				(font
					(size 1.016 1.016)
					(thickness 0.1524)
				)
			)
		)
		(property "Device Type" "LED-1615-4PH26"
			(at -2.132076 -0.109982 0)
			(unlocked yes)
			(layer "F.Fab")
			(hide yes)
			(effects
				(font
					(size 1.016 1.016)
					(thickness 0.1524)
				)
			)
		)
		(duplicate_pad_numbers_are_jumpers no)
		(fp_line
			(start -1.2954 0.254)
			(end -1.2954 1.6002)
			(stroke
				(width 0.508)
				(type default)
			)
			(layer "F.SilkS")
		)
		(fp_line
			(start -1.2954 1.6002)
			(end 1.2954 1.6002)
			(stroke
				(width 0.508)
				(type default)
			)
			(layer "F.SilkS")
		)
		(fp_line
			(start -1.1176 -1.4224)
			(end 1.1176 -1.4224)
			(stroke
				(width 0.1524)
				(type default)
			)
			(layer "F.SilkS")
		)
		(fp_line
			(start -1.1176 1.4224)
			(end -1.1176 -1.4224)
			(stroke
				(width 0.1524)
				(type default)
			)
			(layer "F.SilkS")
		)
		(fp_line
			(start 1.1176 -1.4224)
			(end 1.1176 1.4224)
			(stroke
				(width 0.1524)
				(type default)
			)
			(layer "F.SilkS")
		)
		(fp_line
			(start 1.1176 1.4224)
			(end -1.1176 1.4224)
			(stroke
				(width 0.1524)
				(type default)
			)
			(layer "F.SilkS")
		)
		(fp_line
			(start 1.2954 1.6002)
			(end 1.2954 0.254)
			(stroke
				(width 0.508)
				(type default)
			)
			(layer "F.SilkS")
		)
		(fp_rect
			(start -0.7493 0.8001)
			(end 0.7493 -0.8001)
			(stroke
				(width 0)
				(type default)
			)
			(fill no)
			(layer "F.CrtYd")
		)
		(fp_poly
			(pts
				(xy -1.3716 1.6764) (xy -1.3716 -1.6764) (xy 1.3716 -1.6764) (xy 1.3716 0.0635) (xy 0.7493 0.0635)
				(xy 0.7493 -0.8001) (xy -0.7493 -0.8001) (xy -0.7493 0.8001) (xy 0.7493 0.8001) (xy 0.7493 0.0762)
				(xy 1.3716 0.0762) (xy 1.3716 1.6764)
			)
			(stroke
				(width 0)
				(type default)
			)
			(fill no)
			(layer "F.CrtYd")
		)
		(fp_rect
			(start -1.3716 1.6764)
			(end 1.3716 -1.6764)
			(stroke
				(width 0)
				(type default)
			)
			(fill no)
			(layer "F.Fab")
		)
		(pad "1" smd rect
			(at 0.50038 -0.73025)
			(size 0.7112 0.8636)
			(layers "F.Cu" "F.Mask" "F.Paste")
			(net "DRV_ACT_32")
		)
		(pad "2" smd rect
			(at -0.50038 -0.73025)
			(size 0.7112 0.8636)
			(layers "F.Cu" "F.Mask" "F.Paste")
			(net "FLT_HDD32")
		)
		(pad "3" smd rect
			(at 0.50038 0.73025)
			(size 0.7112 0.8636)
			(layers "F.Cu" "F.Mask" "F.Paste")
			(net "DRV_ACT_32_N")
		)
		(pad "4" smd rect
			(at -0.50038 0.73025)
			(size 0.7112 0.8636)
			(layers "F.Cu" "F.Mask" "F.Paste")
			(net "FLT_HDD32_N")
		)
	)
	(footprint ""
		(layer "F.Cu")
		(at 84.587334 -31.40837 180)
		(property "Reference" "R64"
			(at 0 0 180)
			(layer "F.SilkS")
			(hide yes)
			(effects
				(font
					(size 1.27 1.27)
				)
			)
		)
		(property "Value" "4K7R2F-GP"
			(at 0.064008 -3.993896 180)
			(unlocked yes)
			(layer "F.Fab")
			(hide yes)
			(effects
				(font
					(size 1.016 1.016)
					(thickness 0.1524)
				)
			)
		)
		(property "Device Type" "R402H16"
			(at 0.064008 -5.517896 180)
			(unlocked yes)
			(layer "F.Fab")
			(hide yes)
			(effects
				(font
					(size 1.016 1.016)
					(thickness 0.1524)
				)
			)
		)
		(duplicate_pad_numbers_are_jumpers no)
		(fp_line
			(start 0.508 -0.9398)
			(end -0.508 -0.9398)
			(stroke
				(width 0.1524)
				(type default)
			)
			(layer "F.SilkS")
		)
		(fp_line
			(start -0.508 -0.9398)
			(end -0.508 0.9398)
			(stroke
				(width 0.1524)
				(type default)
			)
			(layer "F.SilkS")
		)
		(fp_rect
			(start -0.508 0.9398)
			(end 0.508 -0.9398)
			(stroke
				(width 0)
				(type default)
			)
			(fill no)
			(layer "F.CrtYd")
		)
		(fp_rect
			(start -0.508 0.9398)
			(end 0.508 -0.9398)
			(stroke
				(width 0)
				(type default)
			)
			(fill no)
			(layer "F.Fab")
		)
		(pad "1" smd custom
			(at 0 -0.4445 180)
			(size 0.1397 0.1397)
			(layers "F.Cu" "F.Mask" "F.Paste")
			(net "IO_EXP10_A0")
			(options
				(clearance outline)
				(anchor circle)
			)
			(primitives
				(gr_poly
					(pts
						(arc
							(start -0.1778 -0.2794)
							(mid -0.249642 -0.249642)
							(end -0.2794 -0.1778)
						)
						(arc
							(start -0.2794 0.1778)
							(mid -0.249642 0.249642)
							(end -0.1778 0.2794)
						)
						(arc
							(start 0.1778 0.2794)
							(mid 0.249642 0.249642)
							(end 0.2794 0.1778)
						)
						(arc
							(start 0.2794 -0.1778)
							(mid 0.249642 -0.249642)
							(end 0.1778 -0.2794)
						)
					)
					(width 0)
					(fill yes)
				)
			)
		)
		(pad "2" smd custom
			(at 0 0.4445 180)
			(size 0.1397 0.1397)
			(layers "F.Cu" "F.Mask" "F.Paste")
			(net "GND")
			(options
				(clearance outline)
				(anchor circle)
			)
			(primitives
				(gr_poly
					(pts
						(arc
							(start -0.1778 -0.2794)
							(mid -0.249642 -0.249642)
							(end -0.2794 -0.1778)
						)
						(arc
							(start -0.2794 0.1778)
							(mid -0.249642 0.249642)
							(end -0.1778 0.2794)
						)
						(arc
							(start 0.1778 0.2794)
							(mid 0.249642 0.249642)
							(end 0.2794 0.1778)
						)
						(arc
							(start 0.2794 -0.1778)
							(mid 0.249642 -0.249642)
							(end 0.1778 -0.2794)
						)
					)
					(width 0)
					(fill yes)
				)
			)
		)
	)
	(footprint ""
		(layer "F.Cu")
		(at 224.155 -387.951472 180)
		(property "Reference" "D41"
			(at 0 0 180)
			(layer "F.SilkS")
			(hide yes)
			(effects
				(font
					(size 1.27 1.27)
				)
			)
		)
		(property "Value" "MMPZ5228BPT-GP"
			(at 0 -6.7818 180)
			(unlocked yes)
			(layer "F.Fab")
			(hide yes)
			(effects
				(font
					(size 1.016 1.016)
					(thickness 0.1524)
				)
			)
		)
		(property "Device Type" "SOD323AKH40"
			(at 0 -8.6868 180)
			(unlocked yes)
			(layer "F.Fab")
			(hide yes)
			(effects
				(font
					(size 1.016 1.016)
					(thickness 0.1524)
				)
			)
		)
		(duplicate_pad_numbers_are_jumpers no)
		(fp_line
			(start 0.889 2.159)
			(end -0.889 2.159)
			(stroke
				(width 0.1524)
				(type default)
			)
			(layer "F.SilkS")
		)
		(fp_line
			(start 0.889 -1.9304)
			(end 0.889 2.159)
			(stroke
				(width 0.1524)
				(type default)
			)
			(layer "F.SilkS")
		)
		(fp_line
			(start 0.762 2.0574)
			(end -0.762 2.0574)
			(stroke
				(width 0.508)
				(type default)
			)
			(layer "F.SilkS")
		)
		(fp_line
			(start -0.889 2.159)
			(end -0.889 -1.9304)
			(stroke
				(width 0.1524)
				(type default)
			)
			(layer "F.SilkS")
		)
		(fp_line
			(start -0.889 -1.9304)
			(end 0.889 -1.9304)
			(stroke
				(width 0.1524)
				(type default)
			)
			(layer "F.SilkS")
		)
		(fp_rect
			(start -1.016 2.3114)
			(end 1.016 -2.0066)
			(stroke
				(width 0)
				(type default)
			)
			(fill no)
			(layer "F.CrtYd")
		)
		(fp_poly
			(pts
				(xy -1.016 -2.0066) (xy 1.016 -2.0066) (xy 1.016 2.3114) (xy -1.016 2.3114)
			)
			(stroke
				(width 0)
				(type default)
			)
			(fill no)
			(layer "F.Fab")
		)
		(pad "A" smd rect
			(at 0 -1.143 180)
			(size 0.5588 1.016)
			(layers "F.Cu" "F.Mask" "F.Paste")
			(net "GND")
		)
		(pad "K" smd rect
			(at 0 1.143 180)
			(size 0.5588 1.016)
			(layers "F.Cu" "F.Mask" "F.Paste")
			(net "VCCP_IN")
		)
	)
	(footprint ""
		(layer "F.Cu")
		(at 127.113284 -274.219416 90)
		(property "Reference" "C78"
			(at 0 0 90)
			(layer "F.SilkS")
			(hide yes)
			(effects
				(font
					(size 1.27 1.27)
				)
			)
		)
		(property "Value" "SCD01U16V1KX-GP"
			(at -2.8321 -1.7399 90)
			(unlocked yes)
			(layer "F.Fab")
			(hide yes)
			(effects
				(font
					(size 1.016 1.016)
					(thickness 0.1524)
				)
			)
		)
		(property "Device Type" "C0201H13"
			(at -2.8321 -3.2639 90)
			(unlocked yes)
			(layer "F.Fab")
			(hide yes)
			(effects
				(font
					(size 1.016 1.016)
					(thickness 0.1524)
				)
			)
		)
		(duplicate_pad_numbers_are_jumpers no)
		(fp_rect
			(start -0.2794 0.6477)
			(end 0.2794 -0.6477)
			(stroke
				(width 0)
				(type default)
			)
			(fill no)
			(layer "F.CrtYd")
		)
		(fp_rect
			(start -0.2794 0.6477)
			(end 0.2794 -0.6477)
			(stroke
				(width 0)
				(type default)
			)
			(fill no)
			(layer "F.Fab")
		)
		(pad "1" smd custom
			(at 0 -0.2794 90)
			(size 0.0762 0.0762)
			(layers "F.Cu" "F.Mask" "F.Paste")
			(net "SAS_HDD_RX_N3")
			(options
				(clearance outline)
				(anchor circle)
			)
			(primitives
				(gr_poly
					(pts
						(arc
							(start 0.1524 -0.127)
							(mid 0.137521 -0.162921)
							(end 0.1016 -0.1778)
						)
						(arc
							(start -0.1016 -0.1778)
							(mid -0.137521 -0.162921)
							(end -0.1524 -0.127)
						)
						(arc
							(start -0.1524 0.127)
							(mid -0.137521 0.162921)
							(end -0.1016 0.1778)
						)
						(arc
							(start 0.1016 0.1778)
							(mid 0.137521 0.162921)
							(end 0.1524 0.127)
						)
					)
					(width 0)
					(fill yes)
				)
			)
		)
		(pad "2" smd custom
			(at 0 0.2794 90)
			(size 0.0762 0.0762)
			(layers "F.Cu" "F.Mask" "F.Paste")
			(net "PHY_SCC_A_TO_DRV_A_3_DN")
			(options
				(clearance outline)
				(anchor circle)
			)
			(primitives
				(gr_poly
					(pts
						(arc
							(start 0.1524 -0.127)
							(mid 0.137521 -0.162921)
							(end 0.1016 -0.1778)
						)
						(arc
							(start -0.1016 -0.1778)
							(mid -0.137521 -0.162921)
							(end -0.1524 -0.127)
						)
						(arc
							(start -0.1524 0.127)
							(mid -0.137521 0.162921)
							(end -0.1016 0.1778)
						)
						(arc
							(start 0.1016 0.1778)
							(mid 0.137521 0.162921)
							(end 0.1524 0.127)
						)
					)
					(width 0)
					(fill yes)
				)
			)
		)
	)
	(footprint ""
		(layer "F.Cu")
		(at 336.931 -275.735542 180)
		(property "Reference" "R282"
			(at 0 0 180)
			(layer "F.SilkS")
			(hide yes)
			(effects
				(font
					(size 1.27 1.27)
				)
			)
		)
		(property "Value" "4K7R2J-2-GP"
			(at 0.064008 -3.993896 180)
			(unlocked yes)
			(layer "F.Fab")
			(hide yes)
			(effects
				(font
					(size 1.016 1.016)
					(thickness 0.1524)
				)
			)
		)
		(property "Device Type" "R402H16"
			(at 0.064008 -5.517896 180)
			(unlocked yes)
			(layer "F.Fab")
			(hide yes)
			(effects
				(font
					(size 1.016 1.016)
					(thickness 0.1524)
				)
			)
		)
		(duplicate_pad_numbers_are_jumpers no)
		(fp_line
			(start 0.508 -0.9398)
			(end -0.508 -0.9398)
			(stroke
				(width 0.1524)
				(type default)
			)
			(layer "F.SilkS")
		)
		(fp_line
			(start -0.508 -0.9398)
			(end -0.508 0.9398)
			(stroke
				(width 0.1524)
				(type default)
			)
			(layer "F.SilkS")
		)
		(fp_rect
			(start -0.508 0.9398)
			(end 0.508 -0.9398)
			(stroke
				(width 0)
				(type default)
			)
			(fill no)
			(layer "F.CrtYd")
		)
		(fp_rect
			(start -0.508 0.9398)
			(end 0.508 -0.9398)
			(stroke
				(width 0)
				(type default)
			)
			(fill no)
			(layer "F.Fab")
		)
		(pad "1" smd custom
			(at 0 -0.4445 180)
			(size 0.1397 0.1397)
			(layers "F.Cu" "F.Mask" "F.Paste")
			(net "P12V_A")
			(options
				(clearance outline)
				(anchor circle)
			)
			(primitives
				(gr_poly
					(pts
						(arc
							(start -0.1778 -0.2794)
							(mid -0.249642 -0.249642)
							(end -0.2794 -0.1778)
						)
						(arc
							(start -0.2794 0.1778)
							(mid -0.249642 0.249642)
							(end -0.1778 0.2794)
						)
						(arc
							(start 0.1778 0.2794)
							(mid 0.249642 0.249642)
							(end 0.2794 0.1778)
						)
						(arc
							(start 0.2794 -0.1778)
							(mid 0.249642 -0.249642)
							(end 0.1778 -0.2794)
						)
					)
					(width 0)
					(fill yes)
				)
			)
		)
		(pad "2" smd custom
			(at 0 0.4445 180)
			(size 0.1397 0.1397)
			(layers "F.Cu" "F.Mask" "F.Paste")
			(net "SW_HDD_R6")
			(options
				(clearance outline)
				(anchor circle)
			)
			(primitives
				(gr_poly
					(pts
						(arc
							(start -0.1778 -0.2794)
							(mid -0.249642 -0.249642)
							(end -0.2794 -0.1778)
						)
						(arc
							(start -0.2794 0.1778)
							(mid -0.249642 0.249642)
							(end -0.1778 0.2794)
						)
						(arc
							(start 0.1778 0.2794)
							(mid 0.249642 0.249642)
							(end 0.2794 0.1778)
						)
						(arc
							(start 0.2794 -0.1778)
							(mid 0.249642 -0.249642)
							(end 0.1778 -0.2794)
						)
					)
					(width 0)
					(fill yes)
				)
			)
		)
	)
	(footprint ""
		(layer "F.Cu")
		(at 178.181 -278.554942 180)
		(property "Reference" "Q31"
			(at 0 0 180)
			(layer "F.SilkS")
			(hide yes)
			(effects
				(font
					(size 1.27 1.27)
				)
			)
		)
		(property "Value" "2N7002KDW-GP"
			(at -2.3622 -8.2042 180)
			(unlocked yes)
			(layer "F.Fab")
			(hide yes)
			(effects
				(font
					(size 1.016 1.016)
					(thickness 0.1524)
				)
			)
		)
		(property "Device Type" "SOT-363H44"
			(at -2.3622 -10.1092 180)
			(unlocked yes)
			(layer "F.Fab")
			(hide yes)
			(effects
				(font
					(size 1.016 1.016)
					(thickness 0.1524)
				)
			)
		)
		(duplicate_pad_numbers_are_jumpers no)
		(fp_line
			(start 1.4478 1.7018)
			(end 1.4478 -1.7018)
			(stroke
				(width 0.1524)
				(type default)
			)
			(layer "F.SilkS")
		)
		(fp_line
			(start 1.4478 -1.7018)
			(end -1.4478 -1.7018)
			(stroke
				(width 0.1524)
				(type default)
			)
			(layer "F.SilkS")
		)
		(fp_line
			(start -1.27 1.524)
			(end -1.27 0.6604)
			(stroke
				(width 0.4826)
				(type default)
			)
			(layer "F.SilkS")
		)
		(fp_line
			(start -1.4478 1.7018)
			(end 1.4478 1.7018)
			(stroke
				(width 0.1524)
				(type default)
			)
			(layer "F.SilkS")
		)
		(fp_line
			(start -1.4478 -1.7018)
			(end -1.4478 1.7018)
			(stroke
				(width 0.1524)
				(type default)
			)
			(layer "F.SilkS")
		)
		(fp_poly
			(pts
				(xy -1.524 -1.778) (xy 1.524 -1.778) (xy 1.524 1.778) (xy -1.524 1.778)
			)
			(stroke
				(width 0)
				(type default)
			)
			(fill no)
			(layer "F.CrtYd")
		)
		(fp_poly
			(pts
				(xy -1.524 -1.778) (xy 1.524 -1.778) (xy 1.524 1.778) (xy -1.524 1.778)
			)
			(stroke
				(width 0)
				(type default)
			)
			(fill no)
			(layer "F.Fab")
		)
		(pad "1" smd rect
			(at -0.65024 0.9398 180)
			(size 0.4064 1.016)
			(layers "F.Cu" "F.Mask" "F.Paste")
			(net "GND")
		)
		(pad "2" smd rect
			(at 0 0.9398 180)
			(size 0.4064 1.016)
			(layers "F.Cu" "F.Mask" "F.Paste")
			(net "SW_PWR_R_HDD5")
		)
		(pad "3" smd rect
			(at 0.65024 0.9398 180)
			(size 0.4064 1.016)
			(layers "F.Cu" "F.Mask" "F.Paste")
			(net "SW_HDD_P5")
		)
		(pad "4" smd rect
			(at 0.65024 -0.9398 180)
			(size 0.4064 1.016)
			(layers "F.Cu" "F.Mask" "F.Paste")
			(net "GND")
		)
		(pad "5" smd rect
			(at 0 -0.9398 180)
			(size 0.4064 1.016)
			(layers "F.Cu" "F.Mask" "F.Paste")
			(net "SW_HDD_G5")
		)
		(pad "6" smd rect
			(at -0.65024 -0.9398 180)
			(size 0.4064 1.016)
			(layers "F.Cu" "F.Mask" "F.Paste")
			(net "SW_HDD_R5")
		)
	)
	(footprint ""
		(layer "F.Cu")
		(at 424.469052 -66.842894 180)
		(property "Reference" "C469"
			(at 0 0 180)
			(layer "F.SilkS")
			(hide yes)
			(effects
				(font
					(size 1.27 1.27)
				)
			)
		)
		(property "Value" "SC1U16V3KX-5GP"
			(at 0 -2.8194 180)
			(unlocked yes)
			(layer "F.Fab")
			(hide yes)
			(effects
				(font
					(size 1.016 1.016)
					(thickness 0.1524)
				)
			)
		)
		(property "Device Type" "C603H36"
			(at 0 -4.3434 180)
			(unlocked yes)
			(layer "F.Fab")
			(hide yes)
			(effects
				(font
					(size 1.016 1.016)
					(thickness 0.1524)
				)
			)
		)
		(duplicate_pad_numbers_are_jumpers no)
		(fp_line
			(start 0.508 0)
			(end -0.508 0)
			(stroke
				(width 0.2032)
				(type default)
			)
			(layer "F.SilkS")
		)
		(fp_rect
			(start -0.5842 1.3335)
			(end 0.5842 -1.3335)
			(stroke
				(width 0)
				(type default)
			)
			(fill no)
			(layer "F.CrtYd")
		)
		(fp_rect
			(start -0.5842 1.3335)
			(end 0.5842 -1.3335)
			(stroke
				(width 0)
				(type default)
			)
			(fill no)
			(layer "F.Fab")
		)
		(pad "1" smd custom
			(at 0 -0.762 180)
			(size 0.2159 0.2159)
			(layers "F.Cu" "F.Mask" "F.Paste")
			(net "P5V_HDD33")
			(options
				(clearance outline)
				(anchor circle)
			)
			(primitives
				(gr_poly
					(pts
						(arc
							(start -0.3302 -0.4318)
							(mid -0.402042 -0.402042)
							(end -0.4318 -0.3302)
						)
						(arc
							(start -0.4318 0.3302)
							(mid -0.402042 0.402042)
							(end -0.3302 0.4318)
						)
						(arc
							(start 0.3302 0.4318)
							(mid 0.402042 0.402042)
							(end 0.4318 0.3302)
						)
						(arc
							(start 0.4318 -0.3302)
							(mid 0.402042 -0.402042)
							(end 0.3302 -0.4318)
						)
					)
					(width 0)
					(fill yes)
				)
			)
		)
		(pad "2" smd custom
			(at 0 0.762 180)
			(size 0.2159 0.2159)
			(layers "F.Cu" "F.Mask" "F.Paste")
			(net "GND")
			(options
				(clearance outline)
				(anchor circle)
			)
			(primitives
				(gr_poly
					(pts
						(arc
							(start -0.3302 -0.4318)
							(mid -0.402042 -0.402042)
							(end -0.4318 -0.3302)
						)
						(arc
							(start -0.4318 0.3302)
							(mid -0.402042 0.402042)
							(end -0.3302 0.4318)
						)
						(arc
							(start 0.3302 0.4318)
							(mid 0.402042 0.402042)
							(end 0.4318 0.3302)
						)
						(arc
							(start 0.4318 -0.3302)
							(mid 0.402042 -0.402042)
							(end 0.3302 -0.4318)
						)
					)
					(width 0)
					(fill yes)
				)
			)
		)
	)
)
